# TIMECARD (Time Appliance Project (Time Card)) — schematic netlist excerpt (pin names and nets, part order shuffled) for the footprints in the layout excerpt that follows; sources: Cadence DE-HDL packaged netlist, KiCad conversion of R4006-B0001-02_R01.brd

R185  RESISTOR  4.22KOHM 1%  pkg SMC_0402R  page 30 : \1\ = XP1R2V_FPGA ; \2\ = XP1R2V_FB
R339  RESISTOR  33OHM 1%  pkg SMC_0402R_H016  page 11 : \1\ = FPGA_D02 ; \2\ = FPGA_FLASH_DQ2

(kicad_pcb
	(version 20260206)
	(generator "pcbnew")
	(generator_version "10.0")
	(general
		(thickness 1.6)
		(legacy_teardrops no)
	)
	(paper "A4")
	(title_block
		(title "timecard-production-celestica-r4006 — R4006-B0001-02_R01.brd")
		(comment 1 "Time Appliance Project (Time Card) / footprints 318-319 of 1113")
	)
	(layers
		(0 "F.Cu" signal "TOP")
		(4 "In1.Cu" signal "L02_GND1")
		(6 "In2.Cu" signal "L03_SIG1")
		(8 "In3.Cu" signal "L04_GND2")
		(10 "In4.Cu" signal "L05_VCC1")
		(12 "In5.Cu" signal "L06_VCC2")
		(14 "In6.Cu" signal "L07_GND3")
		(16 "In7.Cu" signal "L08_SIG2")
		(18 "In8.Cu" signal "L09_GND4")
		(2 "B.Cu" signal "BOTTOM")
		(9 "F.Adhes" user "F.Adhesive")
		(11 "B.Adhes" user "B.Adhesive")
		(13 "F.Paste" user "Package Geometry/Pastemask Top")
		(15 "B.Paste" user "Package Geometry/Pastemask Bottom")
		(5 "F.SilkS" user "Ref Des/Silkscreen Top")
		(7 "B.SilkS" user "Ref Des/Silkscreen Bottom")
		(1 "F.Mask" user "Board Geometry/Soldermask Top")
		(3 "B.Mask" user "Board Geometry/Soldermask Bottom")
		(17 "Dwgs.User" user "User.Drawings")
		(19 "Cmts.User" user "User.Comments")
		(21 "Eco1.User" user "User.Eco1")
		(23 "Eco2.User" user "User.Eco2")
		(25 "Edge.Cuts" user "Board Geometry/Outline")
		(27 "Margin" user)
		(31 "F.CrtYd" user "Package Geometry/Place Bound Top")
		(29 "B.CrtYd" user "Package Geometry/Place Bound Bottom")
		(35 "F.Fab" user "Ref Des/Assembly Top")
		(33 "B.Fab" user "Ref Des/Assembly Bottom")
	)
	(footprint ""
		(layer "F.Cu")
		(at 97.4598 -70.485)
		(property "Reference" "R185"
			(at -28.1178 -18.75663 0)
			(unlocked yes)
			(layer "F.SilkS")
			(effects
				(font
					(size 0.7874 0.5842)
					(thickness 0.1524)
				)
			)
		)
		(property "Value" "VAL*"
			(at 0.0508 2.245106 0)
			(unlocked yes)
			(layer "F.Fab")
			(hide yes)
			(effects
				(font
					(size 0.7874 0.5842)
					(thickness 0.1524)
				)
			)
		)
		(property "User Part Number" "PARTNUM*"
			(at 0.0762 4.302506 0)
			(unlocked yes)
			(layer "Cmts.User")
			(hide yes)
			(effects
				(font
					(size 0.7874 0.5842)
					(thickness 0.1524)
				)
			)
		)
		(property "Device Type" "RESISTOR-G155-04221-01,4.22KOHA"
			(at 0.0762 1.254506 0)
			(unlocked yes)
			(layer "F.Fab")
			(hide yes)
			(effects
				(font
					(size 0.7874 0.5842)
					(thickness 0.1524)
				)
			)
		)
		(property "Tolerance" "TOL*"
			(at 0.0508 3.261106 0)
			(unlocked yes)
			(layer "Cmts.User")
			(hide yes)
			(effects
				(font
					(size 0.7874 0.5842)
					(thickness 0.1524)
				)
			)
		)
		(duplicate_pad_numbers_are_jumpers no)
		(fp_line
			(start -1.143 -0.5588)
			(end -1.143 0.5588)
			(stroke
				(width 0.1)
				(type default)
			)
			(layer "F.SilkS")
		)
		(fp_line
			(start -1.143 0.5588)
			(end 1.143 0.5588)
			(stroke
				(width 0.1)
				(type default)
			)
			(layer "F.SilkS")
		)
		(fp_line
			(start 1.143 -0.5588)
			(end -1.143 -0.5588)
			(stroke
				(width 0.1)
				(type default)
			)
			(layer "F.SilkS")
		)
		(fp_line
			(start 1.143 0.5588)
			(end 1.143 -0.5588)
			(stroke
				(width 0.1)
				(type default)
			)
			(layer "F.SilkS")
		)
		(fp_rect
			(start -1.143 -0.5588)
			(end 1.143 0.5588)
			(stroke
				(width 0)
				(type default)
			)
			(fill no)
			(layer "F.CrtYd")
		)
		(fp_line
			(start -0.508 -0.3048)
			(end -0.508 0.3048)
			(stroke
				(width 0.1)
				(type default)
			)
			(layer "F.Fab")
		)
		(fp_line
			(start -0.508 0.3048)
			(end 0.508 0.3048)
			(stroke
				(width 0.1)
				(type default)
			)
			(layer "F.Fab")
		)
		(fp_line
			(start 0.508 -0.3048)
			(end -0.508 -0.3048)
			(stroke
				(width 0.1)
				(type default)
			)
			(layer "F.Fab")
		)
		(fp_line
			(start 0.508 0.3048)
			(end 0.508 -0.3048)
			(stroke
				(width 0.1)
				(type default)
			)
			(layer "F.Fab")
		)
		(pad "1" smd rect
			(at -0.5334 0)
			(size 0.7112 0.6096)
			(layers "F.Cu" "F.Mask" "F.Paste")
			(net "XP1R2V_FPGA")
		)
		(pad "2" smd rect
			(at 0.5334 0)
			(size 0.7112 0.6096)
			(layers "F.Cu" "F.Mask" "F.Paste")
			(net "XP1R2V_FB")
		)
		(zone
			(layer "F.Cu")
			(hatch none 0.5)
			(connect_pads
				(clearance 0)
			)
			(min_thickness 0.25)
			(keepout
				(tracks allowed)
				(vias not_allowed)
				(pads allowed)
				(copperpour not_allowed)
				(footprints allowed)
			)
			(placement
				(enabled no)
				(sheetname "")
			)
			(fill
				(thermal_gap 0.5)
				(thermal_bridge_width 0.5)
				(island_removal_mode 0)
			)
			(polygon
				(pts
					(xy 97.3836 -70.7898) (xy 97.3836 -70.1802) (xy 97.536 -70.1802) (xy 97.536 -70.7898)
				)
			)
		)
	)
	(footprint ""
		(layer "F.Cu")
		(at 115.062 -61.976 90)
		(property "Reference" "R339"
			(at 3.302 0.29337 90)
			(unlocked yes)
			(layer "F.SilkS")
			(effects
				(font
					(size 0.7874 0.5842)
					(thickness 0.1524)
				)
			)
		)
		(property "Value" "VAL*"
			(at 0.02032 2.13233 90)
			(unlocked yes)
			(layer "F.Fab")
			(hide yes)
			(effects
				(font
					(size 0.7874 0.5842)
					(thickness 0.1524)
				)
			)
		)
		(property "Tolerance" "TOL*"
			(at 0.044704 3.05435 90)
			(unlocked yes)
			(layer "Cmts.User")
			(hide yes)
			(effects
				(font
					(size 0.7874 0.5842)
					(thickness 0.1524)
				)
			)
		)
		(property "User Part Number" "PARTNUM*"
			(at 0.02032 4.024884 90)
			(unlocked yes)
			(layer "Cmts.User")
			(hide yes)
			(effects
				(font
					(size 0.7874 0.5842)
					(thickness 0.1524)
				)
			)
		)
		(property "Device Type" "RESISTOR-G155-133R0-01,33OHM,1%"
			(at 0.008382 1.210564 90)
			(unlocked yes)
			(layer "F.Fab")
			(hide yes)
			(effects
				(font
					(size 0.7874 0.5842)
					(thickness 0.1524)
				)
			)
		)
		(duplicate_pad_numbers_are_jumpers no)
		(fp_line
			(start 1.143 -0.5588)
			(end -1.143 -0.5588)
			(stroke
				(width 0.1)
				(type default)
			)
			(layer "F.SilkS")
		)
		(fp_line
			(start -1.143 -0.5588)
			(end -1.143 0.5588)
			(stroke
				(width 0.1)
				(type default)
			)
			(layer "F.SilkS")
		)
		(fp_line
			(start 1.143 0.5588)
			(end 1.143 -0.5588)
			(stroke
				(width 0.1)
				(type default)
			)
			(layer "F.SilkS")
		)
		(fp_line
			(start -1.143 0.5588)
			(end 1.143 0.5588)
			(stroke
				(width 0.1)
				(type default)
			)
			(layer "F.SilkS")
		)
		(fp_poly
			(pts
				(xy -1.143 0.5588) (xy 1.143 0.5588) (xy 1.143 -0.5588) (xy -1.143 -0.5588)
			)
			(stroke
				(width 0)
				(type default)
			)
			(fill no)
			(layer "F.CrtYd")
		)
		(fp_line
			(start 0.508 -0.3048)
			(end -0.508 -0.3048)
			(stroke
				(width 0.1)
				(type default)
			)
			(layer "F.Fab")
		)
		(fp_line
			(start -0.508 -0.3048)
			(end -0.508 0.3048)
			(stroke
				(width 0.1)
				(type default)
			)
			(layer "F.Fab")
		)
		(fp_line
			(start 0.508 0.3048)
			(end 0.508 -0.3048)
			(stroke
				(width 0.1)
				(type default)
			)
			(layer "F.Fab")
		)
		(fp_line
			(start -0.508 0.3048)
			(end 0.508 0.3048)
			(stroke
				(width 0.1)
				(type default)
			)
			(layer "F.Fab")
		)
		(pad "1" smd rect
			(at -0.5334 0 90)
			(size 0.7112 0.6096)
			(layers "F.Cu" "F.Mask" "F.Paste")
			(net "FPGA_D02")
		)
		(pad "2" smd rect
			(at 0.5334 0 90)
			(size 0.7112 0.6096)
			(layers "F.Cu" "F.Mask" "F.Paste")
			(net "FPGA_FLASH_DQ2")
		)
		(zone
			(layer "F.Cu")
			(hatch none 0.5)
			(connect_pads
				(clearance 0)
			)
			(min_thickness 0.25)
			(keepout
				(tracks not_allowed)
				(vias allowed)
				(pads allowed)
				(copperpour not_allowed)
				(footprints allowed)
			)
			(placement
				(enabled no)
				(sheetname "")
			)
			(fill
				(thermal_gap 0.5)
				(thermal_bridge_width 0.5)
				(island_removal_mode 0)
			)
			(polygon
				(pts
					(xy 115.3668 -61.8998) (xy 115.3668 -62.0522) (xy 114.7572 -62.0522) (xy 114.7572 -61.8998)
				)
			)
		)
		(zone
			(layer "F.Cu")
			(hatch none 0.5)
			(connect_pads
				(clearance 0)
			)
			(min_thickness 0.25)
			(keepout
				(tracks allowed)
				(vias not_allowed)
				(pads allowed)
				(copperpour not_allowed)
				(footprints allowed)
			)
			(placement
				(enabled no)
				(sheetname "")
			)
			(fill
				(thermal_gap 0.5)
				(thermal_bridge_width 0.5)
				(island_removal_mode 0)
			)
			(polygon
				(pts
					(xy 115.3668 -61.8998) (xy 115.3668 -62.0522) (xy 114.7572 -62.0522) (xy 114.7572 -61.8998)
				)
			)
		)
	)
)
